# T6G (Grand Teton) — schematic netlist excerpt (pin names and nets, part order shuffled) for the footprints in the layout excerpt that follows; sources: Cadence DE-HDL packaged netlist, KiCad conversion of 04192023_DAF0TMB3IC0_F0TG_MB_C_brd_V02_OCP.brd

C2192  Q_CAP  22UF 4V 20% X6S  pkg C0402  page 69 : A = PVDDCR_CPU0_P0 ; B = GND
PR193  Q_RES  2.2 1% CHIP  pkg 0402LF  page 212 : A = PVDDCR_CPU0_P1_PVCC ; B = PVDDCR_CPU0_P1_VCC3

(kicad_pcb
	(version 20260206)
	(generator "pcbnew")
	(generator_version "10.0")
	(general
		(thickness 1.6)
		(legacy_teardrops no)
	)
	(paper "A4")
	(title_block
		(title "04192023_DAF0TMB3IC0_F0TG_MB_C_brd_V02_OCP.brd")
		(comment 1 "Grand Teton / footprints 6604-6605 of 8354")
	)
	(layers
		(0 "F.Cu" signal "TOP")
		(4 "In1.Cu" signal "GND")
		(6 "In2.Cu" signal "IN1")
		(8 "In3.Cu" signal "GND1")
		(10 "In4.Cu" signal "IN2")
		(12 "In5.Cu" signal "GND2")
		(14 "In6.Cu" signal "IN3")
		(16 "In7.Cu" signal "GND3")
		(18 "In8.Cu" signal "VCC")
		(20 "In9.Cu" signal "VCC1")
		(22 "In10.Cu" signal "GND4")
		(24 "In11.Cu" signal "IN4")
		(26 "In12.Cu" signal "GND5")
		(28 "In13.Cu" signal "IN5")
		(30 "In14.Cu" signal "GND6")
		(32 "In15.Cu" signal "IN6")
		(34 "In16.Cu" signal "GND7")
		(2 "B.Cu" signal "BOTTOM")
		(9 "F.Adhes" user "F.Adhesive")
		(11 "B.Adhes" user "B.Adhesive")
		(13 "F.Paste" user "Package Geometry/Pastemask Top")
		(15 "B.Paste" user "Package Geometry/Pastemask Bottom")
		(5 "F.SilkS" user "Ref Des/Silkscreen Top")
		(7 "B.SilkS" user "Ref Des/Silkscreen Bottom")
		(1 "F.Mask" user "Board Geometry/Soldermask Top")
		(3 "B.Mask" user "Board Geometry/Soldermask Bottom")
		(17 "Dwgs.User" user "User.Drawings")
		(19 "Cmts.User" user "User.Comments")
		(21 "Eco1.User" user "User.Eco1")
		(23 "Eco2.User" user "User.Eco2")
		(25 "Edge.Cuts" user "Board Geometry/Outline")
		(27 "Margin" user)
		(31 "F.CrtYd" user "Package Geometry/Place Bound Top")
		(29 "B.CrtYd" user "Package Geometry/Place Bound Bottom")
		(35 "F.Fab" user "Ref Des/Assembly Top")
		(33 "B.Fab" user "Ref Des/Assembly Bottom")
	)
	(footprint ""
		(layer "B.Cu")
		(at 370.122958 -245.487952)
		(property "Reference" "C2192"
			(at 0 0 0)
			(layer "B.SilkS")
			(hide yes)
			(effects
				(font
					(size 1.27 1.27)
				)
				(justify mirror)
			)
		)
		(property "Value" ""
			(at 0 0 0)
			(layer "B.Fab")
			(effects
				(font
					(size 1.27 1.27)
				)
				(justify mirror)
			)
		)
		(duplicate_pad_numbers_are_jumpers no)
		(fp_line
			(start -0.7874 -0.4064)
			(end -0.7874 0.4064)
			(stroke
				(width 0.1524)
				(type default)
			)
			(layer "B.SilkS")
		)
		(fp_line
			(start -0.7874 0.4064)
			(end 0.7874 0.4064)
			(stroke
				(width 0.1524)
				(type default)
			)
			(layer "B.SilkS")
		)
		(fp_line
			(start 0.7874 -0.4064)
			(end -0.7874 -0.4064)
			(stroke
				(width 0.1524)
				(type default)
			)
			(layer "B.SilkS")
		)
		(fp_line
			(start 0.7874 0.4064)
			(end 0.7874 -0.4064)
			(stroke
				(width 0.1524)
				(type default)
			)
			(layer "B.SilkS")
		)
		(fp_line
			(start -0.67945 -0.3048)
			(end -0.67945 0.3048)
			(stroke
				(width 0.1)
				(type default)
			)
			(layer "B.Fab")
		)
		(fp_line
			(start -0.67945 0.3048)
			(end -0.120396 0.3048)
			(stroke
				(width 0.1)
				(type default)
			)
			(layer "B.Fab")
		)
		(fp_line
			(start -0.12065 -0.3048)
			(end -0.67945 -0.3048)
			(stroke
				(width 0.1)
				(type default)
			)
			(layer "B.Fab")
		)
		(fp_line
			(start -0.12065 -0.2794)
			(end -0.12065 -0.3048)
			(stroke
				(width 0.1)
				(type default)
			)
			(layer "B.Fab")
		)
		(fp_line
			(start -0.120396 0.2794)
			(end 0.12065 0.2794)
			(stroke
				(width 0.1)
				(type default)
			)
			(layer "B.Fab")
		)
		(fp_line
			(start -0.120396 0.3048)
			(end -0.120396 0.2794)
			(stroke
				(width 0.1)
				(type default)
			)
			(layer "B.Fab")
		)
		(fp_line
			(start 0.12065 -0.305054)
			(end 0.12065 -0.2794)
			(stroke
				(width 0.1)
				(type default)
			)
			(layer "B.Fab")
		)
		(fp_line
			(start 0.12065 -0.2794)
			(end -0.12065 -0.2794)
			(stroke
				(width 0.1)
				(type default)
			)
			(layer "B.Fab")
		)
		(fp_line
			(start 0.12065 0.2794)
			(end 0.12065 0.3048)
			(stroke
				(width 0.1)
				(type default)
			)
			(layer "B.Fab")
		)
		(fp_line
			(start 0.12065 0.3048)
			(end 0.67945 0.3048)
			(stroke
				(width 0.1)
				(type default)
			)
			(layer "B.Fab")
		)
		(fp_line
			(start 0.67945 -0.305054)
			(end 0.12065 -0.305054)
			(stroke
				(width 0.1)
				(type default)
			)
			(layer "B.Fab")
		)
		(fp_line
			(start 0.67945 0.3048)
			(end 0.67945 -0.305054)
			(stroke
				(width 0.1)
				(type default)
			)
			(layer "B.Fab")
		)
		(pad "1" smd circle
			(at 0.40005 0 180)
			(size 0 0)
			(layers "B.Cu" "B.Mask" "B.Paste")
			(net "PVDDCR_CPU0_P0")
		)
		(pad "2" smd circle
			(at -0.40005 0 180)
			(size 0 0)
			(layers "B.Cu" "B.Mask" "B.Paste")
			(net "GND")
		)
	)
	(footprint ""
		(layer "B.Cu")
		(at 101.384862 -181.633876 90)
		(property "Reference" "PR193"
			(at 0 0 90)
			(layer "B.SilkS")
			(hide yes)
			(effects
				(font
					(size 1.27 1.27)
				)
				(justify mirror)
			)
		)
		(property "Value" ""
			(at 0 0 90)
			(layer "B.Fab")
			(effects
				(font
					(size 1.27 1.27)
				)
				(justify mirror)
			)
		)
		(duplicate_pad_numbers_are_jumpers no)
		(fp_line
			(start 0.7874 -0.4064)
			(end -0.7874 -0.4064)
			(stroke
				(width 0.1524)
				(type default)
			)
			(layer "B.SilkS")
		)
		(fp_line
			(start -0.7874 -0.4064)
			(end -0.7874 0.4064)
			(stroke
				(width 0.1524)
				(type default)
			)
			(layer "B.SilkS")
		)
		(fp_line
			(start 0.7874 0.4064)
			(end 0.7874 -0.4064)
			(stroke
				(width 0.1524)
				(type default)
			)
			(layer "B.SilkS")
		)
		(fp_line
			(start -0.7874 0.4064)
			(end 0.7874 0.4064)
			(stroke
				(width 0.1524)
				(type default)
			)
			(layer "B.SilkS")
		)
		(fp_line
			(start 0.67945 -0.305054)
			(end 0.12065 -0.305054)
			(stroke
				(width 0.1)
				(type default)
			)
			(layer "B.Fab")
		)
		(fp_line
			(start 0.12065 -0.305054)
			(end 0.12065 -0.2794)
			(stroke
				(width 0.1)
				(type default)
			)
			(layer "B.Fab")
		)
		(fp_line
			(start -0.12065 -0.3048)
			(end -0.67945 -0.3048)
			(stroke
				(width 0.1)
				(type default)
			)
			(layer "B.Fab")
		)
		(fp_line
			(start -0.67945 -0.3048)
			(end -0.67945 0.3048)
			(stroke
				(width 0.1)
				(type default)
			)
			(layer "B.Fab")
		)
		(fp_line
			(start 0.12065 -0.2794)
			(end -0.12065 -0.2794)
			(stroke
				(width 0.1)
				(type default)
			)
			(layer "B.Fab")
		)
		(fp_line
			(start -0.12065 -0.2794)
			(end -0.12065 -0.3048)
			(stroke
				(width 0.1)
				(type default)
			)
			(layer "B.Fab")
		)
		(fp_line
			(start 0.12065 0.2794)
			(end 0.12065 0.3048)
			(stroke
				(width 0.1)
				(type default)
			)
			(layer "B.Fab")
		)
		(fp_line
			(start -0.120396 0.2794)
			(end 0.12065 0.2794)
			(stroke
				(width 0.1)
				(type default)
			)
			(layer "B.Fab")
		)
		(fp_line
			(start 0.67945 0.3048)
			(end 0.67945 -0.305054)
			(stroke
				(width 0.1)
				(type default)
			)
			(layer "B.Fab")
		)
		(fp_line
			(start 0.12065 0.3048)
			(end 0.67945 0.3048)
			(stroke
				(width 0.1)
				(type default)
			)
			(layer "B.Fab")
		)
		(fp_line
			(start -0.120396 0.3048)
			(end -0.120396 0.2794)
			(stroke
				(width 0.1)
				(type default)
			)
			(layer "B.Fab")
		)
		(fp_line
			(start -0.67945 0.3048)
			(end -0.120396 0.3048)
			(stroke
				(width 0.1)
				(type default)
			)
			(layer "B.Fab")
		)
		(pad "1" smd circle
			(at 0.40005 0 270)
			(size 0 0)
			(layers "B.Cu" "B.Mask" "B.Paste")
			(net "PVDDCR_CPU0_P1_PVCC")
		)
		(pad "2" smd circle
			(at -0.40005 0 270)
			(size 0 0)
			(layers "B.Cu" "B.Mask" "B.Paste")
			(net "PVDDCR_CPU0_P1_VCC3")
		)
	)
)
